(kicad_pcb
	(version 20241229)
	(generator "pcbnew")
	(generator_version "9.0")
	(general
		(thickness 1.62)
		(legacy_teardrops no)
	)
	(paper "A3")
	(title_block
		(title "COM Express 7 Baseboard")
		(date "2025-02-04")
		(rev "1.1.2")
		(company "Antmicro Ltd")
		(comment 1 "www.antmicro.com")
		(comment 9 "footprints 170-174 of 802")
	)
	(layers
		(0 "F.Cu" signal)
		(4 "In1.Cu" signal)
		(6 "In2.Cu" signal)
		(8 "In3.Cu" signal)
		(10 "In4.Cu" signal)
		(12 "In5.Cu" signal)
		(14 "In6.Cu" signal)
		(2 "B.Cu" signal)
		(9 "F.Adhes" user "F.Adhesive")
		(11 "B.Adhes" user "B.Adhesive")
		(13 "F.Paste" user)
		(15 "B.Paste" user)
		(5 "F.SilkS" user "F.Silkscreen")
		(7 "B.SilkS" user "B.Silkscreen")
		(1 "F.Mask" user)
		(3 "B.Mask" user)
		(17 "Dwgs.User" user "User.Drawings")
		(19 "Cmts.User" user "User.Comments")
		(21 "Eco1.User" user "User.Eco1")
		(23 "Eco2.User" user "User.Eco2")
		(25 "Edge.Cuts" user)
		(27 "Margin" user)
		(31 "F.CrtYd" user "F.Courtyard")
		(29 "B.CrtYd" user "B.Courtyard")
		(35 "F.Fab" user)
		(33 "B.Fab" user)
	)
	(footprint "antmicro-footprints:R_0402_1005Metric"
		(layer "F.Cu")
		(at 219.73 125.9)
		(descr "Resistor SMD 0402")
		(tags "resistor SMD 0402")
		(property "Reference" "R189"
			(at 0.77 0.46 0)
			(layer "F.SilkS")
			(effects
				(font
					(size 0.7 0.7)
					(thickness 0.15)
				)
				(justify left bottom)
			)
		)
		(property "Value" "R_1k_0402"
			(at -1.011843 1.772047 0)
			(layer "F.Fab")
			(effects
				(font
					(size 0.7 0.7)
					(thickness 0.15)
				)
				(justify left bottom)
			)
		)
		(property "Datasheet" "https://www.bourns.com/docs/product-datasheets/cr.pdf"
			(at 0 0 0)
			(layer "F.Fab")
			(hide yes)
			(effects
				(font
					(size 1.27 1.27)
					(thickness 0.15)
				)
			)
		)
		(property "Author" "Antmicro"
			(at 0 0 0)
			(layer "F.Fab")
			(hide yes)
			(effects
				(font
					(size 1 1)
					(thickness 0.15)
				)
			)
		)
		(property "License" "Apache-2.0"
			(at 0 0 0)
			(layer "F.Fab")
			(hide yes)
			(effects
				(font
					(size 1 1)
					(thickness 0.15)
				)
			)
		)
		(property "MPN" "CR0402-FX-1001GLF"
			(at 0 0 0)
			(layer "F.Fab")
			(hide yes)
			(effects
				(font
					(size 1 1)
					(thickness 0.15)
				)
			)
		)
		(property "Manufacturer" "Bourns"
			(at 0 0 0)
			(layer "F.Fab")
			(hide yes)
			(effects
				(font
					(size 1 1)
					(thickness 0.15)
				)
			)
		)
		(property "Public" "False"
			(at 0 0 0)
			(layer "F.Fab")
			(hide yes)
			(effects
				(font
					(size 1 1)
					(thickness 0.15)
				)
			)
		)
		(property "Tolerance" "1%"
			(at 0 0 0)
			(layer "F.Fab")
			(hide yes)
			(effects
				(font
					(size 1 1)
					(thickness 0.15)
				)
			)
		)
		(property "Val" "1k"
			(at 0 0 0)
			(layer "F.Fab")
			(hide yes)
			(effects
				(font
					(size 1 1)
					(thickness 0.15)
				)
			)
		)
		(sheetname "PCIe misc")
		(sheetfile "pcie_misc.kicad_sch")
		(attr smd)
		(fp_rect
			(start -0.925 -0.47)
			(end 0.925 0.47)
			(stroke
				(width 0.05)
				(type default)
			)
			(fill no)
			(layer "F.CrtYd")
		)
		(fp_rect
			(start -0.5 -0.25)
			(end 0.5 0.25)
			(stroke
				(width 0.15)
				(type solid)
			)
			(fill no)
			(layer "F.Fab")
		)
		(pad "1" smd roundrect
			(at -0.48 0)
			(size 0.59 0.64)
			(layers "F.Cu" "F.Mask" "F.Paste")
			(roundrect_rratio 0.25)
			(net 608 "Net-(U37-~{OE5})")
			(pintype "passive")
			(teardrops
				(best_length_ratio 0.2)
				(max_length 1)
				(best_width_ratio 0.9)
				(max_width 2)
				(curved_edges yes)
				(filter_ratio 0.9)
				(enabled yes)
				(allow_two_segments yes)
				(prefer_zone_connections yes)
			)
		)
		(pad "2" smd roundrect
			(at 0.48 0)
			(size 0.59 0.64)
			(layers "F.Cu" "F.Mask" "F.Paste")
			(roundrect_rratio 0.25)
			(net 2 "+3V3")
			(pintype "passive")
			(teardrops
				(best_length_ratio 0.2)
				(max_length 1)
				(best_width_ratio 0.9)
				(max_width 2)
				(curved_edges yes)
				(filter_ratio 0.9)
				(enabled yes)
				(allow_two_segments yes)
				(prefer_zone_connections yes)
			)
		)
	)
	(footprint "antmicro-footprints:TP_SMD_0.75mm"
		(layer "F.Cu")
		(at 118.25 73.41 90)
		(property "Reference" "TP7"
			(at 3.9 6.55 0)
			(layer "F.SilkS")
			(effects
				(font
					(size 0.7 0.7)
					(thickness 0.15)
				)
				(justify left bottom)
			)
		)
		(property "Value" "TP_0.75mm_SMD"
			(at 0 1.2 90)
			(layer "F.Fab")
			(effects
				(font
					(size 0.7 0.7)
					(thickness 0.15)
				)
				(justify left bottom)
			)
		)
		(property "Author" "Antmicro"
			(at 191.66 -44.84 0)
			(layer "F.Fab")
			(hide yes)
			(effects
				(font
					(size 1 1)
					(thickness 0.15)
				)
			)
		)
		(property "License" "Apache-2.0"
			(at 191.66 -44.84 0)
			(layer "F.Fab")
			(hide yes)
			(effects
				(font
					(size 1 1)
					(thickness 0.15)
				)
			)
		)
		(property "MPN" ""
			(at 191.66 -44.84 0)
			(layer "F.Fab")
			(hide yes)
			(effects
				(font
					(size 1 1)
					(thickness 0.15)
				)
			)
		)
		(property "Manufacturer" ""
			(at 191.66 -44.84 0)
			(layer "F.Fab")
			(hide yes)
			(effects
				(font
					(size 1 1)
					(thickness 0.15)
				)
			)
		)
		(property "Public" "False"
			(at 191.66 -44.84 0)
			(layer "F.Fab")
			(hide yes)
			(effects
				(font
					(size 1 1)
					(thickness 0.15)
				)
			)
		)
		(sheetname "USB-C console")
		(sheetfile "usb-c_console.kicad_sch")
		(attr exclude_from_pos_files exclude_from_bom)
		(fp_circle
			(center 0 0)
			(end 0.475 0)
			(stroke
				(width 0.05)
				(type default)
			)
			(fill no)
			(layer "F.CrtYd")
		)
		(pad "1" smd circle
			(at 0 0 90)
			(size 0.75 0.75)
			(layers "F.Cu" "F.Mask")
			(net 699 "/USB-C console/FTDI_RX")
			(pinfunction "1")
			(pintype "passive")
			(teardrops
				(best_length_ratio 0.4)
				(max_length 1)
				(best_width_ratio 0.9)
				(max_width 2)
				(curved_edges yes)
				(filter_ratio 0.9)
				(enabled yes)
				(allow_two_segments yes)
				(prefer_zone_connections yes)
			)
		)
	)
	(footprint "antmicro-footprints:C_Pol_EIA-D"
		(layer "F.Cu")
		(at 238.8 159.9)
		(property "Reference" "C94"
			(at 1.7 -3.35 0)
			(layer "F.SilkS")
			(effects
				(font
					(size 0.7 0.7)
					(thickness 0.15)
				)
				(justify left top)
			)
		)
		(property "Value" "C_Pol_68u_16V_Panasonic-TQC-D"
			(at 0 3.4 0)
			(layer "F.Fab")
			(effects
				(font
					(size 0.7 0.7)
					(thickness 0.15)
				)
				(justify left top)
			)
		)
		(property "Datasheet" "https://industrial.panasonic.com/sa/products/pt/aluminum-cap-smd/models/16TQC68MYF"
			(at 0 0 0)
			(layer "F.Fab")
			(hide yes)
			(effects
				(font
					(size 1.27 1.27)
					(thickness 0.15)
				)
			)
		)
		(property "Author" "Antmicro"
			(at 343.2 319.42 0)
			(layer "F.Fab")
			(hide yes)
			(effects
				(font
					(size 1 1)
					(thickness 0.15)
				)
			)
		)
		(property "Dielectric" "template_dielectric"
			(at 343.2 319.42 0)
			(layer "F.Fab")
			(hide yes)
			(effects
				(font
					(size 1 1)
					(thickness 0.15)
				)
			)
		)
		(property "License" "Apache-2.0"
			(at 343.2 319.42 0)
			(layer "F.Fab")
			(hide yes)
			(effects
				(font
					(size 1 1)
					(thickness 0.15)
				)
			)
		)
		(property "MPN" "16TQC68MYF"
			(at 343.2 319.42 0)
			(layer "F.Fab")
			(hide yes)
			(effects
				(font
					(size 1 1)
					(thickness 0.15)
				)
			)
		)
		(property "Manufacturer" "Panasonic"
			(at 343.2 319.42 0)
			(layer "F.Fab")
			(hide yes)
			(effects
				(font
					(size 1 1)
					(thickness 0.15)
				)
			)
		)
		(property "Public" "False"
			(at 343.2 319.42 0)
			(layer "F.Fab")
			(hide yes)
			(effects
				(font
					(size 1 1)
					(thickness 0.15)
				)
			)
		)
		(property "Val" "68u"
			(at 343.2 319.42 0)
			(layer "F.Fab")
			(hide yes)
			(effects
				(font
					(size 1 1)
					(thickness 0.15)
				)
			)
		)
		(property "Voltage" "16V"
			(at 343.2 319.42 0)
			(layer "F.Fab")
			(hide yes)
			(effects
				(font
					(size 1 1)
					(thickness 0.15)
				)
			)
		)
		(sheetname "Com Express 7 MGMT")
		(sheetfile "com_express_7_mgmt.kicad_sch")
		(attr smd)
		(fp_line
			(start -4.3 -1.825)
			(end -3.9 -1.825)
			(stroke
				(width 0.12)
				(type solid)
			)
			(layer "F.SilkS")
		)
		(fp_line
			(start -4.1 -2.025)
			(end -4.1 -1.625)
			(stroke
				(width 0.12)
				(type solid)
			)
			(layer "F.SilkS")
		)
		(fp_line
			(start -3.58 -2.2)
			(end 3.6 -2.2)
			(stroke
				(width 0.15)
				(type solid)
			)
			(layer "F.SilkS")
		)
		(fp_line
			(start -3.58 -1.6)
			(end -3.58 -2.2)
			(stroke
				(width 0.15)
				(type solid)
			)
			(layer "F.SilkS")
		)
		(fp_line
			(start -3.58 2.2)
			(end -3.58 1.6)
			(stroke
				(width 0.15)
				(type solid)
			)
			(layer "F.SilkS")
		)
		(fp_line
			(start 3.6 -2.2)
			(end 3.6 -1.6)
			(stroke
				(width 0.15)
				(type solid)
			)
			(layer "F.SilkS")
		)
		(fp_line
			(start 3.6 1.6)
			(end 3.6 2.2)
			(stroke
				(width 0.15)
				(type solid)
			)
			(layer "F.SilkS")
		)
		(fp_line
			(start 3.6 2.2)
			(end -3.58 2.2)
			(stroke
				(width 0.15)
				(type solid)
			)
			(layer "F.SilkS")
		)
		(fp_line
			(start -4.505 1.51)
			(end -4.505 -1.5)
			(stroke
				(width 0.05)
				(type solid)
			)
			(layer "F.CrtYd")
		)
		(fp_line
			(start -3.775 -2.4)
			(end -3.775 -1.5)
			(stroke
				(width 0.05)
				(type solid)
			)
			(layer "F.CrtYd")
		)
		(fp_line
			(start -3.775 -2.4)
			(end 3.77 -2.4)
			(stroke
				(width 0.05)
				(type solid)
			)
			(layer "F.CrtYd")
		)
		(fp_line
			(start -3.775 -1.5)
			(end -4.505 -1.5)
			(stroke
				(width 0.05)
				(type solid)
			)
			(layer "F.CrtYd")
		)
		(fp_line
			(start -3.77 1.51)
			(end -4.505 1.51)
			(stroke
				(width 0.05)
				(type solid)
			)
			(layer "F.CrtYd")
		)
		(fp_line
			(start -3.77 2.4)
			(end -3.77 1.51)
			(stroke
				(width 0.05)
				(type solid)
			)
			(layer "F.CrtYd")
		)
		(fp_line
			(start 3.77 -2.4)
			(end 3.77 -1.51)
			(stroke
				(width 0.05)
				(type solid)
			)
			(layer "F.CrtYd")
		)
		(fp_line
			(start 3.77 -1.51)
			(end 4.505 -1.51)
			(stroke
				(width 0.05)
				(type solid)
			)
			(layer "F.CrtYd")
		)
		(fp_line
			(start 3.77 1.51)
			(end 3.77 2.4)
			(stroke
				(width 0.05)
				(type solid)
			)
			(layer "F.CrtYd")
		)
		(fp_line
			(start 3.77 2.4)
			(end -3.77 2.4)
			(stroke
				(width 0.05)
				(type solid)
			)
			(layer "F.CrtYd")
		)
		(fp_line
			(start 4.505 -1.51)
			(end 4.505 1.5)
			(stroke
				(width 0.05)
				(type solid)
			)
			(layer "F.CrtYd")
		)
		(fp_line
			(start 4.505 1.51)
			(end 3.77 1.51)
			(stroke
				(width 0.05)
				(type solid)
			)
			(layer "F.CrtYd")
		)
		(fp_rect
			(start -3.65 -2.15)
			(end 3.65 2.15)
			(stroke
				(width 0.15)
				(type solid)
			)
			(fill no)
			(layer "F.Fab")
		)
		(pad "1" smd roundrect
			(at -3.1 0)
			(size 2.31 2.52)
			(layers "F.Cu" "F.Mask" "F.Paste")
			(roundrect_rratio 0.1)
			(net 65 "+12V")
			(pintype "passive")
			(teardrops
				(best_length_ratio 0.2)
				(max_length 1)
				(best_width_ratio 0.9)
				(max_width 2)
				(curved_edges yes)
				(filter_ratio 0.9)
				(enabled yes)
				(allow_two_segments yes)
				(prefer_zone_connections yes)
			)
		)
		(pad "2" smd roundrect
			(at 3.1 0)
			(size 2.31 2.52)
			(layers "F.Cu" "F.Mask" "F.Paste")
			(roundrect_rratio 0.1)
			(net 1 "GND")
			(pintype "passive")
			(teardrops
				(best_length_ratio 0.2)
				(max_length 1)
				(best_width_ratio 0.9)
				(max_width 2)
				(curved_edges yes)
				(filter_ratio 0.9)
				(enabled yes)
				(allow_two_segments yes)
				(prefer_zone_connections yes)
			)
		)
	)
	(footprint "antmicro-footprints:C_0402_1005Metric"
		(layer "F.Cu")
		(at 129.5 111.19 -90)
		(descr "Capacitor SMD 0402")
		(tags "capacitor SMD 0402")
		(property "Reference" "C14"
			(at -0.98 0.5 90)
			(layer "F.SilkS")
			(effects
				(font
					(size 0.7 0.7)
					(thickness 0.15)
				)
				(justify right bottom)
			)
		)
		(property "Value" "C_100n_0402"
			(at -1.022927 2.155213 90)
			(layer "F.Fab")
			(effects
				(font
					(size 0.7 0.7)
					(thickness 0.15)
				)
				(justify right bottom)
			)
		)
		(property "Datasheet" "https://www.murata.com/products/productdetail?partno=GRM155R61H104KE14%23"
			(at 0 0 270)
			(layer "F.Fab")
			(hide yes)
			(effects
				(font
					(size 1.27 1.27)
					(thickness 0.15)
				)
			)
		)
		(property "Author" "Antmicro"
			(at 18.31 240.69 0)
			(layer "F.Fab")
			(hide yes)
			(effects
				(font
					(size 1 1)
					(thickness 0.15)
				)
			)
		)
		(property "Dielectric" "X5R"
			(at 18.31 240.69 0)
			(layer "F.Fab")
			(hide yes)
			(effects
				(font
					(size 1 1)
					(thickness 0.15)
				)
			)
		)
		(property "License" "Apache-2.0"
			(at 18.31 240.69 0)
			(layer "F.Fab")
			(hide yes)
			(effects
				(font
					(size 1 1)
					(thickness 0.15)
				)
			)
		)
		(property "MPN" "GRM155R61H104KE14D"
			(at 18.31 240.69 0)
			(layer "F.Fab")
			(hide yes)
			(effects
				(font
					(size 1 1)
					(thickness 0.15)
				)
			)
		)
		(property "Manufacturer" "Murata"
			(at 18.31 240.69 0)
			(layer "F.Fab")
			(hide yes)
			(effects
				(font
					(size 1 1)
					(thickness 0.15)
				)
			)
		)
		(property "Public" "False"
			(at 18.31 240.69 0)
			(layer "F.Fab")
			(hide yes)
			(effects
				(font
					(size 1 1)
					(thickness 0.15)
				)
			)
		)
		(property "Val" "100n"
			(at 18.31 240.69 0)
			(layer "F.Fab")
			(hide yes)
			(effects
				(font
					(size 1 1)
					(thickness 0.15)
				)
			)
		)
		(property "Voltage" "50V"
			(at 18.31 240.69 0)
			(layer "F.Fab")
			(hide yes)
			(effects
				(font
					(size 1 1)
					(thickness 0.15)
				)
			)
		)
		(sheetname "2xUSB3.0+RJ45")
		(sheetfile "usb3+rj45.kicad_sch")
		(attr smd)
		(fp_rect
			(start -0.925 -0.47)
			(end 0.925 0.47)
			(stroke
				(width 0.05)
				(type default)
			)
			(fill no)
			(layer "F.CrtYd")
		)
		(fp_line
			(start -0.494 0.248)
			(end -0.494 -0.25)
			(stroke
				(width 0.15)
				(type solid)
			)
			(layer "F.Fab")
		)
		(fp_line
			(start 0.504 0.248)
			(end -0.494 0.248)
			(stroke
				(width 0.15)
				(type solid)
			)
			(layer "F.Fab")
		)
		(fp_line
			(start -0.494 -0.25)
			(end 0.504 -0.25)
			(stroke
				(width 0.15)
				(type solid)
			)
			(layer "F.Fab")
		)
		(fp_line
			(start 0.504 -0.25)
			(end 0.504 0.248)
			(stroke
				(width 0.15)
				(type solid)
			)
			(layer "F.Fab")
		)
		(pad "1" smd roundrect
			(at -0.48 0 270)
			(size 0.59 0.64)
			(layers "F.Cu" "F.Mask" "F.Paste")
			(roundrect_rratio 0.25)
			(net 51 "Net-(C13-Pad1)")
			(pintype "passive")
			(teardrops
				(best_length_ratio 0.2)
				(max_length 1)
				(best_width_ratio 0.9)
				(max_width 2)
				(curved_edges yes)
				(filter_ratio 0.9)
				(enabled yes)
				(allow_two_segments yes)
				(prefer_zone_connections yes)
			)
		)
		(pad "2" smd roundrect
			(at 0.48 0 270)
			(size 0.59 0.64)
			(layers "F.Cu" "F.Mask" "F.Paste")
			(roundrect_rratio 0.25)
			(net 1 "GND")
			(pintype "passive")
			(teardrops
				(best_length_ratio 0.2)
				(max_length 1)
				(best_width_ratio 0.9)
				(max_width 2)
				(curved_edges yes)
				(filter_ratio 0.9)
				(enabled yes)
				(allow_two_segments yes)
				(prefer_zone_connections yes)
			)
		)
	)
	(footprint "antmicro-footprints:C_0402_1005Metric"
		(layer "F.Cu")
		(at 310.314499 133.4245 180)
		(descr "Capacitor SMD 0402")
		(tags "capacitor SMD 0402")
		(property "Reference" "C63"
			(at 0.864499 -0.4355 0)
			(layer "F.SilkS")
			(effects
				(font
					(size 0.7 0.7)
					(thickness 0.15)
				)
				(justify right bottom)
			)
		)
		(property "Value" "C_1u_0402"
			(at -1.022927 2.155213 0)
			(layer "F.Fab")
			(effects
				(font
					(size 0.7 0.7)
					(thickness 0.15)
				)
				(justify right bottom)
			)
		)
		(property "Datasheet" "https://product.tdk.com/en/search/capacitor/ceramic/mlcc/info?part_no=C1005X6S1A105K050BC"
			(at 0 0 180)
			(layer "F.Fab")
			(hide yes)
			(effects
				(font
					(size 1.27 1.27)
					(thickness 0.15)
				)
			)
		)
		(property "Author" "Antmicro"
			(at 620.628998 266.849 0)
			(layer "F.Fab")
			(hide yes)
			(effects
				(font
					(size 1 1)
					(thickness 0.15)
				)
			)
		)
		(property "Dielectric" ""
			(at 620.628998 266.849 0)
			(layer "F.Fab")
			(hide yes)
			(effects
				(font
					(size 1 1)
					(thickness 0.15)
				)
			)
		)
		(property "License" "Apache-2.0"
			(at 620.628998 266.849 0)
			(layer "F.Fab")
			(hide yes)
			(effects
				(font
					(size 1 1)
					(thickness 0.15)
				)
			)
		)
		(property "MPN" "C1005X6S1A105K050BC"
			(at 620.628998 266.849 0)
			(layer "F.Fab")
			(hide yes)
			(effects
				(font
					(size 1 1)
					(thickness 0.15)
				)
			)
		)
		(property "Manufacturer" "TDK"
			(at 620.628998 266.849 0)
			(layer "F.Fab")
			(hide yes)
			(effects
				(font
					(size 1 1)
					(thickness 0.15)
				)
			)
		)
		(property "Public" "False"
			(at 620.628998 266.849 0)
			(layer "F.Fab")
			(hide yes)
			(effects
				(font
					(size 1 1)
					(thickness 0.15)
				)
			)
		)
		(property "Val" "1u"
			(at 620.628998 266.849 0)
			(layer "F.Fab")
			(hide yes)
			(effects
				(font
					(size 1 1)
					(thickness 0.15)
				)
			)
		)
		(property "Voltage" ""
			(at 620.628998 266.849 0)
			(layer "F.Fab")
			(hide yes)
			(effects
				(font
					(size 1 1)
					(thickness 0.15)
				)
			)
		)
		(sheetname "Power")
		(sheetfile "power.kicad_sch")
		(attr smd)
		(fp_rect
			(start -0.925 -0.47)
			(end 0.925 0.47)
			(stroke
				(width 0.05)
				(type default)
			)
			(fill no)
			(layer "F.CrtYd")
		)
		(fp_line
			(start 0.504 0.248)
			(end -0.494 0.248)
			(stroke
				(width 0.15)
				(type solid)
			)
			(layer "F.Fab")
		)
		(fp_line
			(start 0.504 -0.25)
			(end 0.504 0.248)
			(stroke
				(width 0.15)
				(type solid)
			)
			(layer "F.Fab")
		)
		(fp_line
			(start -0.494 0.248)
			(end -0.494 -0.25)
			(stroke
				(width 0.15)
				(type solid)
			)
			(layer "F.Fab")
		)
		(fp_line
			(start -0.494 -0.25)
			(end 0.504 -0.25)
			(stroke
				(width 0.15)
				(type solid)
			)
			(layer "F.Fab")
		)
		(pad "1" smd roundrect
			(at -0.48 0 180)
			(size 0.59 0.64)
			(layers "F.Cu" "F.Mask" "F.Paste")
			(roundrect_rratio 0.25)
			(net 1 "GND")
			(pintype "passive")
			(teardrops
				(best_length_ratio 0.2)
				(max_length 1)
				(best_width_ratio 0.9)
				(max_width 2)
				(curved_edges yes)
				(filter_ratio 0.9)
				(enabled yes)
				(allow_two_segments yes)
				(prefer_zone_connections yes)
			)
		)
		(pad "2" smd roundrect
			(at 0.48 0 180)
			(size 0.59 0.64)
			(layers "F.Cu" "F.Mask" "F.Paste")
			(roundrect_rratio 0.25)
			(net 76 "Net-(C63-Pad2)")
			(pintype "passive")
			(teardrops
				(best_length_ratio 0.2)
				(max_length 1)
				(best_width_ratio 0.9)
				(max_width 2)
				(curved_edges yes)
				(filter_ratio 0.9)
				(enabled yes)
				(allow_two_segments yes)
				(prefer_zone_connections yes)
			)
		)
	)
)
